(kicad_pcb
	(version 20241229)
	(generator "pcbnew")
	(generator_version "9.0")
	(general
		(thickness 1.62)
		(legacy_teardrops no)
	)
	(paper "A3")
	(title_block
		(title "COM Express 7 Baseboard")
		(date "2025-02-04")
		(rev "1.1.2")
		(company "Antmicro Ltd")
		(comment 1 "www.antmicro.com")
		(comment 9 "footprints 315-320 of 802")
	)
	(layers
		(0 "F.Cu" signal)
		(4 "In1.Cu" signal)
		(6 "In2.Cu" signal)
		(8 "In3.Cu" signal)
		(10 "In4.Cu" signal)
		(12 "In5.Cu" signal)
		(14 "In6.Cu" signal)
		(2 "B.Cu" signal)
		(9 "F.Adhes" user "F.Adhesive")
		(11 "B.Adhes" user "B.Adhesive")
		(13 "F.Paste" user)
		(15 "B.Paste" user)
		(5 "F.SilkS" user "F.Silkscreen")
		(7 "B.SilkS" user "B.Silkscreen")
		(1 "F.Mask" user)
		(3 "B.Mask" user)
		(17 "Dwgs.User" user "User.Drawings")
		(19 "Cmts.User" user "User.Comments")
		(21 "Eco1.User" user "User.Eco1")
		(23 "Eco2.User" user "User.Eco2")
		(25 "Edge.Cuts" user)
		(27 "Margin" user)
		(31 "F.CrtYd" user "F.Courtyard")
		(29 "B.CrtYd" user "B.Courtyard")
		(35 "F.Fab" user)
		(33 "B.Fab" user)
	)
	(footprint "antmicro-footprints:R_0402_1005Metric"
		(layer "F.Cu")
		(at 126.425 87.060001 180)
		(descr "Resistor SMD 0402")
		(tags "resistor SMD 0402")
		(property "Reference" "R242"
			(at -1.575 -6.4 0)
			(layer "F.SilkS")
			(effects
				(font
					(size 0.7 0.7)
					(thickness 0.15)
				)
				(justify right bottom)
			)
		)
		(property "Value" "R_0R_0402"
			(at -1.011843 1.772047 0)
			(layer "F.Fab")
			(effects
				(font
					(size 0.7 0.7)
					(thickness 0.15)
				)
				(justify right bottom)
			)
		)
		(property "Datasheet" "https://industrial.panasonic.com/cdbs/www-data/pdf/RDA0000/AOA0000C301.pdf"
			(at 0 0 180)
			(layer "F.Fab")
			(hide yes)
			(effects
				(font
					(size 1.27 1.27)
					(thickness 0.15)
				)
			)
		)
		(property "Author" "Antmicro"
			(at 252.85 174.120002 0)
			(layer "F.Fab")
			(hide yes)
			(effects
				(font
					(size 1 1)
					(thickness 0.15)
				)
			)
		)
		(property "Current" "1A"
			(at 252.85 174.120002 0)
			(layer "F.Fab")
			(hide yes)
			(effects
				(font
					(size 1 1)
					(thickness 0.15)
				)
			)
		)
		(property "License" "Apache-2.0"
			(at 252.85 174.120002 0)
			(layer "F.Fab")
			(hide yes)
			(effects
				(font
					(size 1 1)
					(thickness 0.15)
				)
			)
		)
		(property "MPN" "ERJ2GE0R00X"
			(at 252.85 174.120002 0)
			(layer "F.Fab")
			(hide yes)
			(effects
				(font
					(size 1 1)
					(thickness 0.15)
				)
			)
		)
		(property "Manufacturer" "Panasonic"
			(at 252.85 174.120002 0)
			(layer "F.Fab")
			(hide yes)
			(effects
				(font
					(size 1 1)
					(thickness 0.15)
				)
			)
		)
		(property "Public" "False"
			(at 252.85 174.120002 0)
			(layer "F.Fab")
			(hide yes)
			(effects
				(font
					(size 1 1)
					(thickness 0.15)
				)
			)
		)
		(property "Tolerance" ""
			(at 252.85 174.120002 0)
			(layer "F.Fab")
			(hide yes)
			(effects
				(font
					(size 1 1)
					(thickness 0.15)
				)
			)
		)
		(property "Val" "0R"
			(at 252.85 174.120002 0)
			(layer "F.Fab")
			(hide yes)
			(effects
				(font
					(size 1 1)
					(thickness 0.15)
				)
			)
		)
		(sheetname "GPIO expander")
		(sheetfile "gpio_exp.kicad_sch")
		(attr smd)
		(fp_rect
			(start -0.925 -0.47)
			(end 0.925 0.47)
			(stroke
				(width 0.05)
				(type default)
			)
			(fill no)
			(layer "F.CrtYd")
		)
		(fp_rect
			(start -0.5 -0.25)
			(end 0.5 0.25)
			(stroke
				(width 0.15)
				(type solid)
			)
			(fill no)
			(layer "F.Fab")
		)
		(pad "1" smd roundrect
			(at -0.48 0 180)
			(size 0.59 0.64)
			(layers "F.Cu" "F.Mask" "F.Paste")
			(roundrect_rratio 0.25)
			(net 643 "Net-(U41-IO0_4)")
			(pintype "passive")
			(teardrops
				(best_length_ratio 0.2)
				(max_length 1)
				(best_width_ratio 0.9)
				(max_width 2)
				(curved_edges yes)
				(filter_ratio 0.9)
				(enabled yes)
				(allow_two_segments yes)
				(prefer_zone_connections yes)
			)
		)
		(pad "2" smd roundrect
			(at 0.48 0 180)
			(size 0.59 0.64)
			(layers "F.Cu" "F.Mask" "F.Paste")
			(roundrect_rratio 0.25)
			(net 942 "/2xUSB3.0+RJ45/EN_2")
			(pintype "passive")
			(teardrops
				(best_length_ratio 0.2)
				(max_length 1)
				(best_width_ratio 0.9)
				(max_width 2)
				(curved_edges yes)
				(filter_ratio 0.9)
				(enabled yes)
				(allow_two_segments yes)
				(prefer_zone_connections yes)
			)
		)
	)
	(footprint "antmicro-footprints:TP_SMD_0.75mm"
		(layer "F.Cu")
		(at 155.05 129.56)
		(property "Reference" "TP67"
			(at 0.45 -1.25 90)
			(layer "F.SilkS")
			(effects
				(font
					(size 0.7 0.7)
					(thickness 0.15)
				)
				(justify left bottom)
			)
		)
		(property "Value" "TP_0.75mm_SMD"
			(at 0 1.2 0)
			(layer "F.Fab")
			(effects
				(font
					(size 0.7 0.7)
					(thickness 0.15)
				)
				(justify left bottom)
			)
		)
		(property "Author" "Antmicro"
			(at 0 0 0)
			(layer "F.Fab")
			(hide yes)
			(effects
				(font
					(size 1 1)
					(thickness 0.15)
				)
			)
		)
		(property "License" "Apache-2.0"
			(at 0 0 0)
			(layer "F.Fab")
			(hide yes)
			(effects
				(font
					(size 1 1)
					(thickness 0.15)
				)
			)
		)
		(property "MPN" ""
			(at 0 0 0)
			(layer "F.Fab")
			(hide yes)
			(effects
				(font
					(size 1 1)
					(thickness 0.15)
				)
			)
		)
		(property "Manufacturer" ""
			(at 0 0 0)
			(layer "F.Fab")
			(hide yes)
			(effects
				(font
					(size 1 1)
					(thickness 0.15)
				)
			)
		)
		(property "Public" "False"
			(at 0 0 0)
			(layer "F.Fab")
			(hide yes)
			(effects
				(font
					(size 1 1)
					(thickness 0.15)
				)
			)
		)
		(sheetname "KR to SFI #1")
		(sheetfile "kr_sfi.kicad_sch")
		(attr exclude_from_pos_files exclude_from_bom)
		(fp_circle
			(center 0 0)
			(end 0.475 0)
			(stroke
				(width 0.05)
				(type default)
			)
			(fill no)
			(layer "F.CrtYd")
		)
		(pad "1" smd circle
			(at 0 0)
			(size 0.75 0.75)
			(layers "F.Cu" "F.Mask")
			(net 730 "Net-(U43C-CLKOUTA+)")
			(pinfunction "1")
			(pintype "passive")
			(teardrops
				(best_length_ratio 0.4)
				(max_length 1)
				(best_width_ratio 0.9)
				(max_width 2)
				(curved_edges yes)
				(filter_ratio 0.9)
				(enabled yes)
				(allow_two_segments yes)
				(prefer_zone_connections yes)
			)
		)
	)
	(footprint "antmicro-footprints:TP_SMD_0.75mm"
		(layer "F.Cu")
		(at 131.04 128.71)
		(property "Reference" "TP84"
			(at 0.51 -3.3 90)
			(layer "F.SilkS")
			(effects
				(font
					(size 0.7 0.7)
					(thickness 0.15)
				)
				(justify left bottom)
			)
		)
		(property "Value" "TP_0.75mm_SMD"
			(at 0 1.2 0)
			(layer "F.Fab")
			(effects
				(font
					(size 0.7 0.7)
					(thickness 0.15)
				)
				(justify left bottom)
			)
		)
		(property "Author" "Antmicro"
			(at 0 0 0)
			(layer "F.Fab")
			(hide yes)
			(effects
				(font
					(size 1 1)
					(thickness 0.15)
				)
			)
		)
		(property "License" "Apache-2.0"
			(at 0 0 0)
			(layer "F.Fab")
			(hide yes)
			(effects
				(font
					(size 1 1)
					(thickness 0.15)
				)
			)
		)
		(property "MPN" ""
			(at 0 0 0)
			(layer "F.Fab")
			(hide yes)
			(effects
				(font
					(size 1 1)
					(thickness 0.15)
				)
			)
		)
		(property "Manufacturer" ""
			(at 0 0 0)
			(layer "F.Fab")
			(hide yes)
			(effects
				(font
					(size 1 1)
					(thickness 0.15)
				)
			)
		)
		(property "Public" "False"
			(at 0 0 0)
			(layer "F.Fab")
			(hide yes)
			(effects
				(font
					(size 1 1)
					(thickness 0.15)
				)
			)
		)
		(sheetname "KR to SFI #2")
		(sheetfile "kr_sfi.kicad_sch")
		(attr exclude_from_pos_files exclude_from_bom)
		(fp_circle
			(center 0 0)
			(end 0.475 0)
			(stroke
				(width 0.05)
				(type default)
			)
			(fill no)
			(layer "F.CrtYd")
		)
		(pad "1" smd circle
			(at 0 0)
			(size 0.75 0.75)
			(layers "F.Cu" "F.Mask")
			(net 747 "Net-(U45C-PRBS_{PASS})")
			(pinfunction "1")
			(pintype "passive")
			(teardrops
				(best_length_ratio 0.4)
				(max_length 1)
				(best_width_ratio 0.9)
				(max_width 2)
				(curved_edges yes)
				(filter_ratio 0.9)
				(enabled yes)
				(allow_two_segments yes)
				(prefer_zone_connections yes)
			)
		)
	)
	(footprint "antmicro-footprints:TP_SMD_0.75mm"
		(layer "F.Cu")
		(at 152.45 129.56)
		(property "Reference" "TP62"
			(at 0.45 -1.25 90)
			(layer "F.SilkS")
			(effects
				(font
					(size 0.7 0.7)
					(thickness 0.15)
				)
				(justify left bottom)
			)
		)
		(property "Value" "TP_0.75mm_SMD"
			(at 0 1.2 0)
			(layer "F.Fab")
			(effects
				(font
					(size 0.7 0.7)
					(thickness 0.15)
				)
				(justify left bottom)
			)
		)
		(property "Author" "Antmicro"
			(at 0 0 0)
			(layer "F.Fab")
			(hide yes)
			(effects
				(font
					(size 1 1)
					(thickness 0.15)
				)
			)
		)
		(property "License" "Apache-2.0"
			(at 0 0 0)
			(layer "F.Fab")
			(hide yes)
			(effects
				(font
					(size 1 1)
					(thickness 0.15)
				)
			)
		)
		(property "MPN" ""
			(at 0 0 0)
			(layer "F.Fab")
			(hide yes)
			(effects
				(font
					(size 1 1)
					(thickness 0.15)
				)
			)
		)
		(property "Manufacturer" ""
			(at 0 0 0)
			(layer "F.Fab")
			(hide yes)
			(effects
				(font
					(size 1 1)
					(thickness 0.15)
				)
			)
		)
		(property "Public" "False"
			(at 0 0 0)
			(layer "F.Fab")
			(hide yes)
			(effects
				(font
					(size 1 1)
					(thickness 0.15)
				)
			)
		)
		(sheetname "KR to SFI #1")
		(sheetfile "kr_sfi.kicad_sch")
		(attr exclude_from_pos_files exclude_from_bom)
		(fp_circle
			(center 0 0)
			(end 0.475 0)
			(stroke
				(width 0.05)
				(type default)
			)
			(fill no)
			(layer "F.CrtYd")
		)
		(pad "1" smd circle
			(at 0 0)
			(size 0.75 0.75)
			(layers "F.Cu" "F.Mask")
			(net 725 "/2xSFP+/KR to SFI #1/TCK")
			(pinfunction "1")
			(pintype "passive")
			(teardrops
				(best_length_ratio 0.4)
				(max_length 1)
				(best_width_ratio 0.9)
				(max_width 2)
				(curved_edges yes)
				(filter_ratio 0.9)
				(enabled yes)
				(allow_two_segments yes)
				(prefer_zone_connections yes)
			)
		)
	)
	(footprint "antmicro-footprints:LED_0603_1608Metric_G"
		(layer "F.Cu")
		(at 138.62 168.44 180)
		(descr "LED SMD 0603 Green")
		(tags "LED SMD 0603 Green")
		(property "Reference" "D8"
			(at 1.12 -0.42 0)
			(layer "F.SilkS")
			(effects
				(font
					(size 0.7 0.7)
					(thickness 0.15)
				)
				(justify right bottom)
			)
		)
		(property "Value" "LED_G_0603_LTST-C190GKT"
			(at -0.001 1.599 0)
			(layer "F.Fab")
			(effects
				(font
					(size 0.7 0.7)
					(thickness 0.15)
				)
				(justify right bottom)
			)
		)
		(property "Datasheet" "https://media.digikey.com/pdf/Data%20Sheets/Lite-On%20PDFs/LTST-C190GKT.pdf"
			(at 0 0 180)
			(layer "F.Fab")
			(hide yes)
			(effects
				(font
					(size 1.27 1.27)
					(thickness 0.15)
				)
			)
		)
		(property "Author" "Antmicro"
			(at 277.24 336.88 0)
			(layer "F.Fab")
			(hide yes)
			(effects
				(font
					(size 1 1)
					(thickness 0.15)
				)
			)
		)
		(property "Color" "Green"
			(at 277.24 336.88 0)
			(layer "F.Fab")
			(hide yes)
			(effects
				(font
					(size 1 1)
					(thickness 0.15)
				)
			)
		)
		(property "License" "Apache-2.0"
			(at 277.24 336.88 0)
			(layer "F.Fab")
			(hide yes)
			(effects
				(font
					(size 1 1)
					(thickness 0.15)
				)
			)
		)
		(property "MPN" "LTST-C190GKT"
			(at 277.24 336.88 0)
			(layer "F.Fab")
			(hide yes)
			(effects
				(font
					(size 1 1)
					(thickness 0.15)
				)
			)
		)
		(property "Manufacturer" "Lite-On"
			(at 277.24 336.88 0)
			(layer "F.Fab")
			(hide yes)
			(effects
				(font
					(size 1 1)
					(thickness 0.15)
				)
			)
		)
		(property "Public" "False"
			(at 277.24 336.88 0)
			(layer "F.Fab")
			(hide yes)
			(effects
				(font
					(size 1 1)
					(thickness 0.15)
				)
			)
		)
		(sheetname "2xSFP+")
		(sheetfile "2xSFP+.kicad_sch")
		(attr smd)
		(fp_line
			(start 0.22 0.35)
			(end -0.22 0.35)
			(stroke
				(width 0.15)
				(type solid)
			)
			(layer "F.SilkS")
		)
		(fp_line
			(start 0.22 -0.35)
			(end -0.22 -0.35)
			(stroke
				(width 0.15)
				(type solid)
			)
			(layer "F.SilkS")
		)
		(fp_line
			(start 0.105328 0.201008)
			(end 0.105328 -0.198992)
			(stroke
				(width 0.1)
				(type solid)
			)
			(layer "F.SilkS")
		)
		(fp_line
			(start 0.105328 0.201008)
			(end -0.094672 0.001008)
			(stroke
				(width 0.1)
				(type solid)
			)
			(layer "F.SilkS")
		)
		(fp_line
			(start 0.105328 0.001008)
			(end 0.24 0.001)
			(stroke
				(width 0.1)
				(type solid)
			)
			(layer "F.SilkS")
		)
		(fp_line
			(start -0.094672 0.201008)
			(end -0.094672 -0.198992)
			(stroke
				(width 0.1)
				(type solid)
			)
			(layer "F.SilkS")
		)
		(fp_line
			(start -0.094672 0.001008)
			(end 0.105328 -0.198992)
			(stroke
				(width 0.1)
				(type solid)
			)
			(layer "F.SilkS")
		)
		(fp_line
			(start -0.094672 0.001008)
			(end -0.24 0.001008)
			(stroke
				(width 0.1)
				(type solid)
			)
			(layer "F.SilkS")
		)
		(fp_line
			(start -1.18 -0.319)
			(end -1.18 0.321)
			(stroke
				(width 0.15)
				(type solid)
			)
			(layer "F.SilkS")
		)
		(fp_rect
			(start 1.25 0.65)
			(end -1.25 -0.65)
			(stroke
				(width 0.05)
				(type solid)
			)
			(fill no)
			(layer "F.CrtYd")
		)
		(fp_line
			(start 0.599 0)
			(end 0.201 0)
			(stroke
				(width 0.15)
				(type solid)
			)
			(layer "F.Fab")
		)
		(fp_line
			(start 0.201 0.2)
			(end 0.201 0)
			(stroke
				(width 0.15)
				(type solid)
			)
			(layer "F.Fab")
		)
		(fp_line
			(start 0.201 0)
			(end 0.201 -0.202)
			(stroke
				(width 0.15)
				(type solid)
			)
			(layer "F.Fab")
		)
		(fp_line
			(start 0.201 -0.202)
			(end -0.101 0)
			(stroke
				(width 0.15)
				(type solid)
			)
			(layer "F.Fab")
		)
		(fp_line
			(start -0.101 0)
			(end 0.201 0.2)
			(stroke
				(width 0.15)
				(type solid)
			)
			(layer "F.Fab")
		)
		(fp_line
			(start -0.199 0.2)
			(end -0.199 0.1)
			(stroke
				(width 0.15)
				(type solid)
			)
			(layer "F.Fab")
		)
		(fp_line
			(start -0.199 0)
			(end -0.597 0)
			(stroke
				(width 0.15)
				(type solid)
			)
			(layer "F.Fab")
		)
		(fp_line
			(start -0.199 -0.202)
			(end -0.199 0.1)
			(stroke
				(width 0.15)
				(type solid)
			)
			(layer "F.Fab")
		)
		(fp_rect
			(start 0.848 0.4)
			(end -0.85 -0.402)
			(stroke
				(width 0.15)
				(type solid)
			)
			(fill no)
			(layer "F.Fab")
		)
		(pad "1" smd roundrect
			(at -0.7 0)
			(size 0.8 1)
			(layers "F.Cu" "F.Mask" "F.Paste")
			(roundrect_rratio 0.2)
			(net 940 "Net-(D8-C)")
			(pinfunction "C")
			(pintype "passive")
			(teardrops
				(best_length_ratio 0.2)
				(max_length 1)
				(best_width_ratio 0.9)
				(max_width 2)
				(curved_edges yes)
				(filter_ratio 0.9)
				(enabled yes)
				(allow_two_segments yes)
				(prefer_zone_connections yes)
			)
		)
		(pad "2" smd roundrect
			(at 0.7 0)
			(size 0.8 1)
			(layers "F.Cu" "F.Mask" "F.Paste")
			(roundrect_rratio 0.2)
			(net 2 "+3V3")
			(pinfunction "A")
			(pintype "passive")
			(teardrops
				(best_length_ratio 0.2)
				(max_length 1)
				(best_width_ratio 0.9)
				(max_width 2)
				(curved_edges yes)
				(filter_ratio 0.9)
				(enabled yes)
				(allow_two_segments yes)
				(prefer_zone_connections yes)
			)
		)
	)
	(footprint "antmicro-footprints:R_0402_1005Metric"
		(layer "F.Cu")
		(at 248.35 128.31 -90)
		(descr "Resistor SMD 0402")
		(tags "resistor SMD 0402")
		(property "Reference" "R173"
			(at -3.65 -0.4 90)
			(layer "F.SilkS")
			(effects
				(font
					(size 0.7 0.7)
					(thickness 0.15)
				)
				(justify right bottom)
			)
		)
		(property "Value" "R_100k_0402"
			(at -1.011843 1.772047 90)
			(layer "F.Fab")
			(effects
				(font
					(size 0.7 0.7)
					(thickness 0.15)
				)
				(justify right bottom)
			)
		)
		(property "Datasheet" "https://www.bourns.com/docs/product-datasheets/cr.pdf"
			(at 0 0 270)
			(layer "F.Fab")
			(hide yes)
			(effects
				(font
					(size 1.27 1.27)
					(thickness 0.15)
				)
			)
		)
		(property "Author" "Antmicro"
			(at 120.04 376.66 0)
			(layer "F.Fab")
			(hide yes)
			(effects
				(font
					(size 1 1)
					(thickness 0.15)
				)
			)
		)
		(property "License" "Apache-2.0"
			(at 120.04 376.66 0)
			(layer "F.Fab")
			(hide yes)
			(effects
				(font
					(size 1 1)
					(thickness 0.15)
				)
			)
		)
		(property "MPN" "CR0402-FX-1003GLF"
			(at 120.04 376.66 0)
			(layer "F.Fab")
			(hide yes)
			(effects
				(font
					(size 1 1)
					(thickness 0.15)
				)
			)
		)
		(property "Manufacturer" "Bourns"
			(at 120.04 376.66 0)
			(layer "F.Fab")
			(hide yes)
			(effects
				(font
					(size 1 1)
					(thickness 0.15)
				)
			)
		)
		(property "Public" "False"
			(at 120.04 376.66 0)
			(layer "F.Fab")
			(hide yes)
			(effects
				(font
					(size 1 1)
					(thickness 0.15)
				)
			)
		)
		(property "Tolerance" "1%"
			(at 120.04 376.66 0)
			(layer "F.Fab")
			(hide yes)
			(effects
				(font
					(size 1 1)
					(thickness 0.15)
				)
			)
		)
		(property "Val" "100k"
			(at 120.04 376.66 0)
			(layer "F.Fab")
			(hide yes)
			(effects
				(font
					(size 1 1)
					(thickness 0.15)
				)
			)
		)
		(sheetname "Com Express 7 MGMT")
		(sheetfile "com_express_7_mgmt.kicad_sch")
		(attr smd dnp)
		(fp_rect
			(start -0.925 -0.47)
			(end 0.925 0.47)
			(stroke
				(width 0.05)
				(type default)
			)
			(fill no)
			(layer "F.CrtYd")
		)
		(fp_rect
			(start -0.5 -0.25)
			(end 0.5 0.25)
			(stroke
				(width 0.15)
				(type solid)
			)
			(fill no)
			(layer "F.Fab")
		)
		(pad "1" smd roundrect
			(at -0.48 0 270)
			(size 0.59 0.64)
			(layers "F.Cu" "F.Mask" "F.Paste")
			(roundrect_rratio 0.25)
			(net 999 "Net-(C101-Pad1)")
			(pintype "passive")
			(teardrops
				(best_length_ratio 0.2)
				(max_length 1)
				(best_width_ratio 0.9)
				(max_width 2)
				(curved_edges yes)
				(filter_ratio 0.9)
				(enabled yes)
				(allow_two_segments yes)
				(prefer_zone_connections yes)
			)
		)
		(pad "2" smd roundrect
			(at 0.48 0 270)
			(size 0.59 0.64)
			(layers "F.Cu" "F.Mask" "F.Paste")
			(roundrect_rratio 0.25)
			(net 84 "/Com Express 7 MGMT/PWRBTN")
			(pintype "passive")
			(teardrops
				(best_length_ratio 0.2)
				(max_length 1)
				(best_width_ratio 0.9)
				(max_width 2)
				(curved_edges yes)
				(filter_ratio 0.9)
				(enabled yes)
				(allow_two_segments yes)
				(prefer_zone_connections yes)
			)
		)
	)
)
